(kicad_pcb
	(version 20260206)
	(generator "pcbnew")
	(generator_version "10.0")
	(general
		(thickness 1.6)
		(legacy_teardrops no)
	)
	(paper "A4")
	(title_block
		(title "01162023_DA0F0TEBIF0_F0T_Expander_BD_F_brd_V02_OCP.brd")
		(comment 1 "Grand Teton / footprints 8270-8279 of 9728")
	)
	(layers
		(0 "F.Cu" signal "TOP")
		(4 "In1.Cu" signal "GND")
		(6 "In2.Cu" signal "VCC")
		(8 "In3.Cu" signal "VCC1")
		(10 "In4.Cu" signal "GND1")
		(12 "In5.Cu" signal "IN1")
		(14 "In6.Cu" signal "GND2")
		(16 "In7.Cu" signal "IN2")
		(18 "In8.Cu" signal "GND3")
		(20 "In9.Cu" signal "IN3")
		(22 "In10.Cu" signal "GND4")
		(24 "In11.Cu" signal "IN4")
		(26 "In12.Cu" signal "GND5")
		(28 "In13.Cu" signal "IN5")
		(30 "In14.Cu" signal "GND6")
		(32 "In15.Cu" signal "IN6")
		(34 "In16.Cu" signal "GND7")
		(2 "B.Cu" signal "BOTTOM")
		(9 "F.Adhes" user "F.Adhesive")
		(11 "B.Adhes" user "B.Adhesive")
		(13 "F.Paste" user "Package Geometry/Pastemask Top")
		(15 "B.Paste" user "Package Geometry/Pastemask Bottom")
		(5 "F.SilkS" user "Ref Des/Silkscreen Top")
		(7 "B.SilkS" user "Ref Des/Silkscreen Bottom")
		(1 "F.Mask" user "Board Geometry/Soldermask Top")
		(3 "B.Mask" user "Board Geometry/Soldermask Bottom")
		(17 "Dwgs.User" user "User.Drawings")
		(19 "Cmts.User" user "User.Comments")
		(21 "Eco1.User" user "User.Eco1")
		(23 "Eco2.User" user "User.Eco2")
		(25 "Edge.Cuts" user "Board Geometry/Outline")
		(27 "Margin" user)
		(31 "F.CrtYd" user "Package Geometry/Place Bound Top")
		(29 "B.CrtYd" user "Package Geometry/Place Bound Bottom")
		(35 "F.Fab" user "Ref Des/Assembly Top")
		(33 "B.Fab" user "Ref Des/Assembly Bottom")
	)
	(footprint ""
		(layer "B.Cu")
		(at 181.44998 -299.699934 -90)
		(property "Reference" "C1440"
			(at 0 0 90)
			(layer "B.SilkS")
			(hide yes)
			(effects
				(font
					(size 1.27 1.27)
				)
				(justify mirror)
			)
		)
		(property "Value" ""
			(at 0 0 90)
			(layer "B.Fab")
			(effects
				(font
					(size 1.27 1.27)
				)
				(justify mirror)
			)
		)
		(duplicate_pad_numbers_are_jumpers no)
		(fp_line
			(start -0.299974 0.150114)
			(end 0.299974 0.150114)
			(stroke
				(width 0.1)
				(type default)
			)
			(layer "B.Fab")
		)
		(fp_line
			(start 0.299974 0.150114)
			(end 0.299974 -0.150114)
			(stroke
				(width 0.1)
				(type default)
			)
			(layer "B.Fab")
		)
		(fp_line
			(start -0.299974 -0.150114)
			(end -0.299974 0.150114)
			(stroke
				(width 0.1)
				(type default)
			)
			(layer "B.Fab")
		)
		(fp_line
			(start 0.299974 -0.150114)
			(end -0.299974 -0.150114)
			(stroke
				(width 0.1)
				(type default)
			)
			(layer "B.Fab")
		)
		(pad "1" smd rect
			(at 0.2667 0 90)
			(size 0.3048 0.381)
			(layers "B.Cu" "B.Mask" "B.Paste")
			(net "P0V8_SERDES_VDDA_PEX1")
		)
		(pad "2" smd rect
			(at -0.2667 0 90)
			(size 0.3048 0.381)
			(layers "B.Cu" "B.Mask" "B.Paste")
			(net "GND")
		)
	)
	(footprint ""
		(layer "B.Cu")
		(at 460.169006 -286.661606 180)
		(property "Reference" "PC273"
			(at 0 0 0)
			(layer "B.SilkS")
			(hide yes)
			(effects
				(font
					(size 1.27 1.27)
				)
				(justify mirror)
			)
		)
		(property "Value" ""
			(at 0 0 0)
			(layer "B.Fab")
			(effects
				(font
					(size 1.27 1.27)
				)
				(justify mirror)
			)
		)
		(duplicate_pad_numbers_are_jumpers no)
		(fp_line
			(start 1.524 0.762)
			(end 1.524 -0.762)
			(stroke
				(width 0.1524)
				(type default)
			)
			(layer "B.SilkS")
		)
		(fp_line
			(start 1.524 -0.762)
			(end -1.524 -0.762)
			(stroke
				(width 0.1524)
				(type default)
			)
			(layer "B.SilkS")
		)
		(fp_line
			(start -1.524 0.762)
			(end 1.524 0.762)
			(stroke
				(width 0.1524)
				(type default)
			)
			(layer "B.SilkS")
		)
		(fp_line
			(start -1.524 -0.762)
			(end -1.524 0.762)
			(stroke
				(width 0.1524)
				(type default)
			)
			(layer "B.SilkS")
		)
		(fp_line
			(start 1.1049 0.724916)
			(end -1.1049 0.724916)
			(stroke
				(width 0.1)
				(type default)
			)
			(layer "B.Fab")
		)
		(fp_line
			(start 1.1049 -0.724916)
			(end 1.1049 0.724916)
			(stroke
				(width 0.1)
				(type default)
			)
			(layer "B.Fab")
		)
		(fp_line
			(start -1.1049 0.724916)
			(end -1.1049 -0.724916)
			(stroke
				(width 0.1)
				(type default)
			)
			(layer "B.Fab")
		)
		(fp_line
			(start -1.1049 -0.724916)
			(end 1.1049 -0.724916)
			(stroke
				(width 0.1)
				(type default)
			)
			(layer "B.Fab")
		)
		(pad "1" smd rect
			(at 0.889 0 180)
			(size 1.016 1.27)
			(layers "B.Cu" "B.Mask" "B.Paste")
			(net "P1V25_PEX3_R")
		)
		(pad "2" smd rect
			(at -0.889 0 180)
			(size 1.016 1.27)
			(layers "B.Cu" "B.Mask" "B.Paste")
			(net "GND")
		)
	)
	(footprint ""
		(layer "B.Cu")
		(at 58.240168 -297.79976 -90)
		(property "Reference" "C1133"
			(at 0 0 90)
			(layer "B.SilkS")
			(hide yes)
			(effects
				(font
					(size 1.27 1.27)
				)
				(justify mirror)
			)
		)
		(property "Value" ""
			(at 0 0 90)
			(layer "B.Fab")
			(effects
				(font
					(size 1.27 1.27)
				)
				(justify mirror)
			)
		)
		(duplicate_pad_numbers_are_jumpers no)
		(fp_line
			(start -0.299974 0.150114)
			(end 0.299974 0.150114)
			(stroke
				(width 0.1)
				(type default)
			)
			(layer "B.Fab")
		)
		(fp_line
			(start 0.299974 0.150114)
			(end 0.299974 -0.150114)
			(stroke
				(width 0.1)
				(type default)
			)
			(layer "B.Fab")
		)
		(fp_line
			(start -0.299974 -0.150114)
			(end -0.299974 0.150114)
			(stroke
				(width 0.1)
				(type default)
			)
			(layer "B.Fab")
		)
		(fp_line
			(start 0.299974 -0.150114)
			(end -0.299974 -0.150114)
			(stroke
				(width 0.1)
				(type default)
			)
			(layer "B.Fab")
		)
		(pad "1" smd rect
			(at 0.2667 0 90)
			(size 0.3048 0.381)
			(layers "B.Cu" "B.Mask" "B.Paste")
			(net "P0V8_PEX0")
		)
		(pad "2" smd rect
			(at -0.2667 0 90)
			(size 0.3048 0.381)
			(layers "B.Cu" "B.Mask" "B.Paste")
			(net "GND")
		)
	)
	(footprint ""
		(layer "B.Cu")
		(at 169.574972 -297.79976 90)
		(property "Reference" "C1379"
			(at 0 0 90)
			(layer "B.SilkS")
			(hide yes)
			(effects
				(font
					(size 1.27 1.27)
				)
				(justify mirror)
			)
		)
		(property "Value" ""
			(at 0 0 90)
			(layer "B.Fab")
			(effects
				(font
					(size 1.27 1.27)
				)
				(justify mirror)
			)
		)
		(duplicate_pad_numbers_are_jumpers no)
		(fp_line
			(start 0.299974 -0.150114)
			(end -0.299974 -0.150114)
			(stroke
				(width 0.1)
				(type default)
			)
			(layer "B.Fab")
		)
		(fp_line
			(start -0.299974 -0.150114)
			(end -0.299974 0.150114)
			(stroke
				(width 0.1)
				(type default)
			)
			(layer "B.Fab")
		)
		(fp_line
			(start 0.299974 0.150114)
			(end 0.299974 -0.150114)
			(stroke
				(width 0.1)
				(type default)
			)
			(layer "B.Fab")
		)
		(fp_line
			(start -0.299974 0.150114)
			(end 0.299974 0.150114)
			(stroke
				(width 0.1)
				(type default)
			)
			(layer "B.Fab")
		)
		(pad "1" smd rect
			(at 0.2667 0 270)
			(size 0.3048 0.381)
			(layers "B.Cu" "B.Mask" "B.Paste")
			(net "P0V8_PEX1")
		)
		(pad "2" smd rect
			(at -0.2667 0 270)
			(size 0.3048 0.381)
			(layers "B.Cu" "B.Mask" "B.Paste")
			(net "GND")
		)
	)
	(footprint ""
		(layer "B.Cu")
		(at 405.100028 -301.599854 -90)
		(property "Reference" "C1987"
			(at 0 0 90)
			(layer "B.SilkS")
			(hide yes)
			(effects
				(font
					(size 1.27 1.27)
				)
				(justify mirror)
			)
		)
		(property "Value" ""
			(at 0 0 90)
			(layer "B.Fab")
			(effects
				(font
					(size 1.27 1.27)
				)
				(justify mirror)
			)
		)
		(duplicate_pad_numbers_are_jumpers no)
		(fp_line
			(start -0.299974 0.150114)
			(end 0.299974 0.150114)
			(stroke
				(width 0.1)
				(type default)
			)
			(layer "B.Fab")
		)
		(fp_line
			(start 0.299974 0.150114)
			(end 0.299974 -0.150114)
			(stroke
				(width 0.1)
				(type default)
			)
			(layer "B.Fab")
		)
		(fp_line
			(start -0.299974 -0.150114)
			(end -0.299974 0.150114)
			(stroke
				(width 0.1)
				(type default)
			)
			(layer "B.Fab")
		)
		(fp_line
			(start 0.299974 -0.150114)
			(end -0.299974 -0.150114)
			(stroke
				(width 0.1)
				(type default)
			)
			(layer "B.Fab")
		)
		(pad "1" smd rect
			(at 0.2667 0 90)
			(size 0.3048 0.381)
			(layers "B.Cu" "B.Mask" "B.Paste")
			(net "P0V8_SERDES_VDDA_PEX3")
		)
		(pad "2" smd rect
			(at -0.2667 0 90)
			(size 0.3048 0.381)
			(layers "B.Cu" "B.Mask" "B.Paste")
			(net "GND")
		)
	)
	(footprint ""
		(layer "B.Cu")
		(at 281.755342 -154.0256)
		(property "Reference" "R225"
			(at 0 0 0)
			(layer "B.SilkS")
			(hide yes)
			(effects
				(font
					(size 1.27 1.27)
				)
				(justify mirror)
			)
		)
		(property "Value" ""
			(at 0 0 0)
			(layer "B.Fab")
			(effects
				(font
					(size 1.27 1.27)
				)
				(justify mirror)
			)
		)
		(duplicate_pad_numbers_are_jumpers no)
		(fp_line
			(start -0.7874 -0.4064)
			(end -0.7874 0.4064)
			(stroke
				(width 0.1524)
				(type default)
			)
			(layer "B.SilkS")
		)
		(fp_line
			(start -0.7874 0.4064)
			(end 0.7874 0.4064)
			(stroke
				(width 0.1524)
				(type default)
			)
			(layer "B.SilkS")
		)
		(fp_line
			(start 0.7874 -0.4064)
			(end -0.7874 -0.4064)
			(stroke
				(width 0.1524)
				(type default)
			)
			(layer "B.SilkS")
		)
		(fp_line
			(start 0.7874 0.4064)
			(end 0.7874 -0.4064)
			(stroke
				(width 0.1524)
				(type default)
			)
			(layer "B.SilkS")
		)
		(fp_line
			(start -0.67945 -0.3048)
			(end -0.67945 0.3048)
			(stroke
				(width 0.1)
				(type default)
			)
			(layer "B.Fab")
		)
		(fp_line
			(start -0.67945 0.3048)
			(end -0.120396 0.3048)
			(stroke
				(width 0.1)
				(type default)
			)
			(layer "B.Fab")
		)
		(fp_line
			(start -0.12065 -0.3048)
			(end -0.67945 -0.3048)
			(stroke
				(width 0.1)
				(type default)
			)
			(layer "B.Fab")
		)
		(fp_line
			(start -0.12065 -0.2794)
			(end -0.12065 -0.3048)
			(stroke
				(width 0.1)
				(type default)
			)
			(layer "B.Fab")
		)
		(fp_line
			(start -0.120396 0.2794)
			(end 0.12065 0.2794)
			(stroke
				(width 0.1)
				(type default)
			)
			(layer "B.Fab")
		)
		(fp_line
			(start -0.120396 0.3048)
			(end -0.120396 0.2794)
			(stroke
				(width 0.1)
				(type default)
			)
			(layer "B.Fab")
		)
		(fp_line
			(start 0.12065 -0.305054)
			(end 0.12065 -0.2794)
			(stroke
				(width 0.1)
				(type default)
			)
			(layer "B.Fab")
		)
		(fp_line
			(start 0.12065 -0.2794)
			(end -0.12065 -0.2794)
			(stroke
				(width 0.1)
				(type default)
			)
			(layer "B.Fab")
		)
		(fp_line
			(start 0.12065 0.2794)
			(end 0.12065 0.3048)
			(stroke
				(width 0.1)
				(type default)
			)
			(layer "B.Fab")
		)
		(fp_line
			(start 0.12065 0.3048)
			(end 0.67945 0.3048)
			(stroke
				(width 0.1)
				(type default)
			)
			(layer "B.Fab")
		)
		(fp_line
			(start 0.67945 -0.305054)
			(end 0.12065 -0.305054)
			(stroke
				(width 0.1)
				(type default)
			)
			(layer "B.Fab")
		)
		(fp_line
			(start 0.67945 0.3048)
			(end 0.67945 -0.305054)
			(stroke
				(width 0.1)
				(type default)
			)
			(layer "B.Fab")
		)
		(pad "1" smd circle
			(at 0.40005 0 180)
			(size 0 0)
			(layers "B.Cu" "B.Mask" "B.Paste")
			(net "NCSI_NIC4_TX_EN")
		)
		(pad "2" smd circle
			(at -0.40005 0 180)
			(size 0 0)
			(layers "B.Cu" "B.Mask" "B.Paste")
			(net "GND")
		)
	)
	(footprint ""
		(layer "B.Cu")
		(at 299.449744 -303.499774 -90)
		(property "Reference" "C3272"
			(at 0 0 90)
			(layer "B.SilkS")
			(hide yes)
			(effects
				(font
					(size 1.27 1.27)
				)
				(justify mirror)
			)
		)
		(property "Value" ""
			(at 0 0 90)
			(layer "B.Fab")
			(effects
				(font
					(size 1.27 1.27)
				)
				(justify mirror)
			)
		)
		(duplicate_pad_numbers_are_jumpers no)
		(fp_line
			(start -0.299974 0.150114)
			(end 0.299974 0.150114)
			(stroke
				(width 0.1)
				(type default)
			)
			(layer "B.Fab")
		)
		(fp_line
			(start 0.299974 0.150114)
			(end 0.299974 -0.150114)
			(stroke
				(width 0.1)
				(type default)
			)
			(layer "B.Fab")
		)
		(fp_line
			(start -0.299974 -0.150114)
			(end -0.299974 0.150114)
			(stroke
				(width 0.1)
				(type default)
			)
			(layer "B.Fab")
		)
		(fp_line
			(start 0.299974 -0.150114)
			(end -0.299974 -0.150114)
			(stroke
				(width 0.1)
				(type default)
			)
			(layer "B.Fab")
		)
		(pad "1" smd rect
			(at 0.2667 0 90)
			(size 0.3048 0.381)
			(layers "B.Cu" "B.Mask" "B.Paste")
			(net "P1V25_PEX2")
		)
		(pad "2" smd rect
			(at -0.2667 0 90)
			(size 0.3048 0.381)
			(layers "B.Cu" "B.Mask" "B.Paste")
			(net "GND")
		)
	)
	(footprint ""
		(layer "B.Cu")
		(at 334.520286 -308.613556 90)
		(property "Reference" "C4318"
			(at 0 0 90)
			(layer "B.SilkS")
			(hide yes)
			(effects
				(font
					(size 1.27 1.27)
				)
				(justify mirror)
			)
		)
		(property "Value" ""
			(at 0 0 90)
			(layer "B.Fab")
			(effects
				(font
					(size 1.27 1.27)
				)
				(justify mirror)
			)
		)
		(duplicate_pad_numbers_are_jumpers no)
		(fp_line
			(start 1.2954 -0.5842)
			(end -1.2954 -0.5842)
			(stroke
				(width 0.1524)
				(type default)
			)
			(layer "B.SilkS")
		)
		(fp_line
			(start -1.2954 -0.5842)
			(end -1.2954 0.5842)
			(stroke
				(width 0.1524)
				(type default)
			)
			(layer "B.SilkS")
		)
		(fp_line
			(start 1.2954 0.5842)
			(end 1.2954 -0.5842)
			(stroke
				(width 0.1524)
				(type default)
			)
			(layer "B.SilkS")
		)
		(fp_line
			(start -1.2954 0.5842)
			(end 1.2954 0.5842)
			(stroke
				(width 0.1524)
				(type default)
			)
			(layer "B.SilkS")
		)
		(fp_line
			(start 0.8636 -0.4572)
			(end -0.8636 -0.4572)
			(stroke
				(width 0.1)
				(type default)
			)
			(layer "B.Fab")
		)
		(fp_line
			(start -0.8636 -0.4572)
			(end -0.8636 -0.4064)
			(stroke
				(width 0.1)
				(type default)
			)
			(layer "B.Fab")
		)
		(fp_line
			(start 1.1938 -0.4064)
			(end 0.8636 -0.4064)
			(stroke
				(width 0.1)
				(type default)
			)
			(layer "B.Fab")
		)
		(fp_line
			(start 0.8636 -0.4064)
			(end 0.8636 -0.4572)
			(stroke
				(width 0.1)
				(type default)
			)
			(layer "B.Fab")
		)
		(fp_line
			(start -0.8636 -0.4064)
			(end -1.1938 -0.4064)
			(stroke
				(width 0.1)
				(type default)
			)
			(layer "B.Fab")
		)
		(fp_line
			(start -1.1938 -0.4064)
			(end -1.1938 0.4064)
			(stroke
				(width 0.1)
				(type default)
			)
			(layer "B.Fab")
		)
		(fp_line
			(start 1.1938 0.4064)
			(end 1.1938 -0.4064)
			(stroke
				(width 0.1)
				(type default)
			)
			(layer "B.Fab")
		)
		(fp_line
			(start 0.8636 0.4064)
			(end 1.1938 0.4064)
			(stroke
				(width 0.1)
				(type default)
			)
			(layer "B.Fab")
		)
		(fp_line
			(start -0.8636 0.4064)
			(end -0.8636 0.4572)
			(stroke
				(width 0.1)
				(type default)
			)
			(layer "B.Fab")
		)
		(fp_line
			(start -1.1938 0.4064)
			(end -0.8636 0.4064)
			(stroke
				(width 0.1)
				(type default)
			)
			(layer "B.Fab")
		)
		(fp_line
			(start 0.8636 0.4572)
			(end 0.8636 0.4064)
			(stroke
				(width 0.1)
				(type default)
			)
			(layer "B.Fab")
		)
		(fp_line
			(start -0.8636 0.4572)
			(end 0.8636 0.4572)
			(stroke
				(width 0.1)
				(type default)
			)
			(layer "B.Fab")
		)
		(pad "1" smd rect
			(at 0.7366 0)
			(size 0.7112 0.8128)
			(layers "B.Cu" "B.Mask" "B.Paste")
			(net "P0V8_PEX2")
		)
		(pad "2" smd rect
			(at -0.7366 0)
			(size 0.7112 0.8128)
			(layers "B.Cu" "B.Mask" "B.Paste")
			(net "GND")
		)
	)
	(footprint ""
		(layer "B.Cu")
		(at 57.274968 -297.79976 90)
		(property "Reference" "C1118"
			(at 0 0 90)
			(layer "B.SilkS")
			(hide yes)
			(effects
				(font
					(size 1.27 1.27)
				)
				(justify mirror)
			)
		)
		(property "Value" ""
			(at 0 0 90)
			(layer "B.Fab")
			(effects
				(font
					(size 1.27 1.27)
				)
				(justify mirror)
			)
		)
		(duplicate_pad_numbers_are_jumpers no)
		(fp_line
			(start 0.299974 -0.150114)
			(end -0.299974 -0.150114)
			(stroke
				(width 0.1)
				(type default)
			)
			(layer "B.Fab")
		)
		(fp_line
			(start -0.299974 -0.150114)
			(end -0.299974 0.150114)
			(stroke
				(width 0.1)
				(type default)
			)
			(layer "B.Fab")
		)
		(fp_line
			(start 0.299974 0.150114)
			(end 0.299974 -0.150114)
			(stroke
				(width 0.1)
				(type default)
			)
			(layer "B.Fab")
		)
		(fp_line
			(start -0.299974 0.150114)
			(end 0.299974 0.150114)
			(stroke
				(width 0.1)
				(type default)
			)
			(layer "B.Fab")
		)
		(pad "1" smd rect
			(at 0.2667 0 270)
			(size 0.3048 0.381)
			(layers "B.Cu" "B.Mask" "B.Paste")
			(net "P0V8_PEX0")
		)
		(pad "2" smd rect
			(at -0.2667 0 270)
			(size 0.3048 0.381)
			(layers "B.Cu" "B.Mask" "B.Paste")
			(net "GND")
		)
	)
	(footprint ""
		(layer "B.Cu")
		(at 189.500002 -110.978696)
		(property "Reference" "C896"
			(at 0 0 0)
			(layer "B.SilkS")
			(hide yes)
			(effects
				(font
					(size 1.27 1.27)
				)
				(justify mirror)
			)
		)
		(property "Value" ""
			(at 0 0 0)
			(layer "B.Fab")
			(effects
				(font
					(size 1.27 1.27)
				)
				(justify mirror)
			)
		)
		(duplicate_pad_numbers_are_jumpers no)
		(fp_line
			(start -0.299974 -0.150114)
			(end -0.299974 0.150114)
			(stroke
				(width 0.1)
				(type default)
			)
			(layer "B.Fab")
		)
		(fp_line
			(start -0.299974 0.150114)
			(end 0.299974 0.150114)
			(stroke
				(width 0.1)
				(type default)
			)
			(layer "B.Fab")
		)
		(fp_line
			(start 0.299974 -0.150114)
			(end -0.299974 -0.150114)
			(stroke
				(width 0.1)
				(type default)
			)
			(layer "B.Fab")
		)
		(fp_line
			(start 0.299974 0.150114)
			(end 0.299974 -0.150114)
			(stroke
				(width 0.1)
				(type default)
			)
			(layer "B.Fab")
		)
		(pad "1" smd rect
			(at 0.2667 0 180)
			(size 0.3048 0.381)
			(layers "B.Cu" "B.Mask" "B.Paste")
			(net "P12V_NIC3")
		)
		(pad "2" smd rect
			(at -0.2667 0 180)
			(size 0.3048 0.381)
			(layers "B.Cu" "B.Mask" "B.Paste")
			(net "GND")
		)
	)
)
